# BASEBOARD_FAB2 (Tioga Pass) — schematic netlist excerpt (pin names and nets, part order shuffled) for the footprints in the layout excerpt that follows; sources: Cadence DE-HDL packaged netlist, KiCad conversion of Wiwynn_Tioga_Pass_MB.brd

R9F62  RES  0.0 5% CHIP  pkg 0402  page 145 : A = CLK_24M_BMC_CLKIN_R ; B = CLK_24M_25M_BMC_CLKIN
R7D12  RES  10.0K 1% CHIP  pkg 0402  page 133 : A = P3V3_STBY ; B = FM_OCP_MEZZA_PRES
C1F11  CAP  0.22UF 16V 10% X7R  pkg 0402  page 181 : A = P3E_CPU1_PE3_MP_C_TXP<4> ; B = P3E_CPU1_PE3_MP_TXP<4>

(kicad_pcb
	(version 20260206)
	(generator "pcbnew")
	(generator_version "10.0")
	(general
		(thickness 1.6)
		(legacy_teardrops no)
	)
	(paper "A4")
	(title_block
		(title "Wiwynn_Tioga_Pass_MB.brd")
		(comment 1 "Tioga Pass / footprints 2136-2138 of 4770")
	)
	(layers
		(0 "F.Cu" signal "TOP")
		(4 "In1.Cu" signal "L2GND")
		(6 "In2.Cu" signal "L3")
		(8 "In3.Cu" signal "L4GND")
		(10 "In4.Cu" signal "L5")
		(12 "In5.Cu" signal "L6GND")
		(14 "In6.Cu" signal "L7VCC")
		(16 "In7.Cu" signal "L8VCC")
		(18 "In8.Cu" signal "L9GND")
		(20 "In9.Cu" signal "L10")
		(22 "In10.Cu" signal "L11GND")
		(24 "In11.Cu" signal "L12")
		(26 "In12.Cu" signal "L13GND")
		(2 "B.Cu" signal "BOTTOM")
		(9 "F.Adhes" user "F.Adhesive")
		(11 "B.Adhes" user "B.Adhesive")
		(13 "F.Paste" user "Package Geometry/Pastemask Top")
		(15 "B.Paste" user "Package Geometry/Pastemask Bottom")
		(5 "F.SilkS" user "Ref Des/Silkscreen Top")
		(7 "B.SilkS" user "Ref Des/Silkscreen Bottom")
		(1 "F.Mask" user "Board Geometry/Soldermask Top")
		(3 "B.Mask" user "Board Geometry/Soldermask Bottom")
		(17 "Dwgs.User" user "User.Drawings")
		(19 "Cmts.User" user "User.Comments")
		(21 "Eco1.User" user "User.Eco1")
		(23 "Eco2.User" user "User.Eco2")
		(25 "Edge.Cuts" user "Board Geometry/Outline")
		(27 "Margin" user)
		(31 "F.CrtYd" user "Package Geometry/Place Bound Top")
		(29 "B.CrtYd" user "Package Geometry/Place Bound Bottom")
		(35 "F.Fab" user "Ref Des/Assembly Top")
		(33 "B.Fab" user "Ref Des/Assembly Bottom")
	)
	(footprint ""
		(layer "F.Cu")
		(at 385.318 -87.3125 180)
		(property "Reference" "R7D12"
			(at 0 0 180)
			(layer "F.SilkS")
			(hide yes)
			(effects
				(font
					(size 1.27 1.27)
				)
			)
		)
		(property "Value" ""
			(at 0 0 180)
			(layer "F.Fab")
			(effects
				(font
					(size 1.27 1.27)
				)
			)
		)
		(duplicate_pad_numbers_are_jumpers no)
		(fp_poly
			(pts
				(xy -0.2794 -0.1016) (xy 0.2794 -0.1016) (xy 0.2794 0.9906) (xy -0.2794 0.9906)
			)
			(stroke
				(width 0)
				(type default)
			)
			(fill no)
			(layer "F.CrtYd")
		)
		(fp_line
			(start 0.2794 0.9906)
			(end 0.2794 -0.1016)
			(stroke
				(width 0.1)
				(type default)
			)
			(layer "F.Fab")
		)
		(fp_line
			(start 0.2794 -0.1016)
			(end -0.2794 -0.1016)
			(stroke
				(width 0.1)
				(type default)
			)
			(layer "F.Fab")
		)
		(fp_line
			(start -0.2794 0.9906)
			(end 0.2794 0.9906)
			(stroke
				(width 0.1)
				(type default)
			)
			(layer "F.Fab")
		)
		(fp_line
			(start -0.2794 -0.1016)
			(end -0.2794 0.9906)
			(stroke
				(width 0.1)
				(type default)
			)
			(layer "F.Fab")
		)
		(pad "1" smd rect
			(at 0 0 180)
			(size 0.508 0.508)
			(layers "F.Cu" "F.Mask" "F.Paste")
			(net "P3V3_STBY")
		)
		(pad "2" smd rect
			(at 0 0.889 180)
			(size 0.508 0.508)
			(layers "F.Cu" "F.Mask" "F.Paste")
			(net "FM_OCP_MEZZA_PRES")
		)
		(zone
			(layer "F.Cu")
			(hatch none 0.5)
			(connect_pads
				(clearance 0)
			)
			(min_thickness 0.25)
			(keepout
				(tracks not_allowed)
				(vias allowed)
				(pads allowed)
				(copperpour not_allowed)
				(footprints allowed)
			)
			(placement
				(enabled no)
				(sheetname "")
			)
			(fill
				(thermal_gap 0.5)
				(thermal_bridge_width 0.5)
				(island_removal_mode 0)
			)
			(polygon
				(pts
					(xy 385.572 -87.9475) (xy 385.064 -87.9475) (xy 385.064 -87.5665) (xy 385.572 -87.5665)
				)
			)
		)
		(zone
			(layer "F.Cu")
			(hatch none 0.5)
			(connect_pads
				(clearance 0)
			)
			(min_thickness 0.25)
			(keepout
				(tracks allowed)
				(vias not_allowed)
				(pads allowed)
				(copperpour not_allowed)
				(footprints allowed)
			)
			(placement
				(enabled no)
				(sheetname "")
			)
			(fill
				(thermal_gap 0.5)
				(thermal_bridge_width 0.5)
				(island_removal_mode 0)
			)
			(polygon
				(pts
					(xy 385.572 -87.5665) (xy 385.064 -87.5665) (xy 385.064 -87.9475) (xy 385.572 -87.9475)
				)
			)
		)
	)
	(footprint ""
		(layer "F.Cu")
		(at 13.8938 -30.353 90)
		(property "Reference" "C1F11"
			(at 0 0 90)
			(layer "F.SilkS")
			(hide yes)
			(effects
				(font
					(size 1.27 1.27)
				)
			)
		)
		(property "Value" ""
			(at 0 0 90)
			(layer "F.Fab")
			(effects
				(font
					(size 1.27 1.27)
				)
			)
		)
		(duplicate_pad_numbers_are_jumpers no)
		(fp_rect
			(start -0.3048 -0.1016)
			(end 0.3048 0.9906)
			(stroke
				(width 0)
				(type default)
			)
			(fill no)
			(layer "F.CrtYd")
		)
		(fp_line
			(start 0.3048 -0.1016)
			(end -0.3048 -0.1016)
			(stroke
				(width 0.1)
				(type default)
			)
			(layer "F.Fab")
		)
		(fp_line
			(start -0.3048 -0.1016)
			(end -0.3048 0.9906)
			(stroke
				(width 0.1)
				(type default)
			)
			(layer "F.Fab")
		)
		(fp_line
			(start 0.3048 0.9906)
			(end 0.3048 -0.1016)
			(stroke
				(width 0.1)
				(type default)
			)
			(layer "F.Fab")
		)
		(fp_line
			(start -0.3048 0.9906)
			(end 0.3048 0.9906)
			(stroke
				(width 0.1)
				(type default)
			)
			(layer "F.Fab")
		)
		(pad "1" smd rect
			(at 0 0 90)
			(size 0.508 0.508)
			(layers "F.Cu" "F.Mask" "F.Paste")
			(net "P3E_CPU1_PE3_MP_C_TXP<4>")
		)
		(pad "2" smd rect
			(at 0 0.889 90)
			(size 0.508 0.508)
			(layers "F.Cu" "F.Mask" "F.Paste")
			(net "P3E_CPU1_PE3_MP_TXP<4>")
		)
		(zone
			(layer "F.Cu")
			(hatch none 0.5)
			(connect_pads
				(clearance 0)
			)
			(min_thickness 0.25)
			(keepout
				(tracks allowed)
				(vias not_allowed)
				(pads allowed)
				(copperpour not_allowed)
				(footprints allowed)
			)
			(placement
				(enabled no)
				(sheetname "")
			)
			(fill
				(thermal_gap 0.5)
				(thermal_bridge_width 0.5)
				(island_removal_mode 0)
			)
			(polygon
				(pts
					(xy 14.1478 -30.099) (xy 14.5288 -30.099) (xy 14.5288 -30.607) (xy 14.1478 -30.607)
				)
			)
		)
		(zone
			(layer "F.Cu")
			(hatch none 0.5)
			(connect_pads
				(clearance 0)
			)
			(min_thickness 0.25)
			(keepout
				(tracks not_allowed)
				(vias allowed)
				(pads allowed)
				(copperpour not_allowed)
				(footprints allowed)
			)
			(placement
				(enabled no)
				(sheetname "")
			)
			(fill
				(thermal_gap 0.5)
				(thermal_bridge_width 0.5)
				(island_removal_mode 0)
			)
			(polygon
				(pts
					(xy 14.1478 -30.099) (xy 14.5288 -30.099) (xy 14.5288 -30.607) (xy 14.1478 -30.607)
				)
			)
		)
	)
	(footprint ""
		(layer "F.Cu")
		(at 431.766472 -45.05452 -90)
		(property "Reference" "R9F62"
			(at 0 0 270)
			(layer "F.SilkS")
			(hide yes)
			(effects
				(font
					(size 1.27 1.27)
				)
			)
		)
		(property "Value" ""
			(at 0 0 270)
			(layer "F.Fab")
			(effects
				(font
					(size 1.27 1.27)
				)
			)
		)
		(duplicate_pad_numbers_are_jumpers no)
		(fp_poly
			(pts
				(xy -0.2794 -0.1016) (xy 0.2794 -0.1016) (xy 0.2794 0.9906) (xy -0.2794 0.9906)
			)
			(stroke
				(width 0)
				(type default)
			)
			(fill no)
			(layer "F.CrtYd")
		)
		(fp_line
			(start -0.2794 0.9906)
			(end 0.2794 0.9906)
			(stroke
				(width 0.1)
				(type default)
			)
			(layer "F.Fab")
		)
		(fp_line
			(start 0.2794 0.9906)
			(end 0.2794 -0.1016)
			(stroke
				(width 0.1)
				(type default)
			)
			(layer "F.Fab")
		)
		(fp_line
			(start -0.2794 -0.1016)
			(end -0.2794 0.9906)
			(stroke
				(width 0.1)
				(type default)
			)
			(layer "F.Fab")
		)
		(fp_line
			(start 0.2794 -0.1016)
			(end -0.2794 -0.1016)
			(stroke
				(width 0.1)
				(type default)
			)
			(layer "F.Fab")
		)
		(pad "1" smd rect
			(at 0 0 270)
			(size 0.508 0.508)
			(layers "F.Cu" "F.Mask" "F.Paste")
			(net "CLK_24M_BMC_CLKIN_R")
		)
		(pad "2" smd rect
			(at 0 0.889 270)
			(size 0.508 0.508)
			(layers "F.Cu" "F.Mask" "F.Paste")
			(net "CLK_24M_25M_BMC_CLKIN")
		)
		(zone
			(layer "F.Cu")
			(hatch none 0.5)
			(connect_pads
				(clearance 0)
			)
			(min_thickness 0.25)
			(keepout
				(tracks not_allowed)
				(vias allowed)
				(pads allowed)
				(copperpour not_allowed)
				(footprints allowed)
			)
			(placement
				(enabled no)
				(sheetname "")
			)
			(fill
				(thermal_gap 0.5)
				(thermal_bridge_width 0.5)
				(island_removal_mode 0)
			)
			(polygon
				(pts
					(xy 431.131472 -45.30852) (xy 431.131472 -44.80052) (xy 431.512472 -44.80052) (xy 431.512472 -45.30852)
				)
			)
		)
		(zone
			(layer "F.Cu")
			(hatch none 0.5)
			(connect_pads
				(clearance 0)
			)
			(min_thickness 0.25)
			(keepout
				(tracks allowed)
				(vias not_allowed)
				(pads allowed)
				(copperpour not_allowed)
				(footprints allowed)
			)
			(placement
				(enabled no)
				(sheetname "")
			)
			(fill
				(thermal_gap 0.5)
				(thermal_bridge_width 0.5)
				(island_removal_mode 0)
			)
			(polygon
				(pts
					(xy 431.512472 -45.30852) (xy 431.512472 -44.80052) (xy 431.131472 -44.80052) (xy 431.131472 -45.30852)
				)
			)
		)
	)
)
